FILE_TYPE=LIBRARY_PARTS;
primitive '74LV4052PW';
  pin
    '2Y0':
      PIN_NUMBER='(1)';
      BIDIRECTIONAL='TRUE';
      INPUT_LOAD='(-0.01,0.01)';
      OUTPUT_LOAD='(1.0,-1.0)';
    '2Y2':
      PIN_NUMBER='(2)';
      BIDIRECTIONAL='TRUE';
      INPUT_LOAD='(-0.01,0.01)';
      OUTPUT_LOAD='(1.0,-1.0)';
    '2Z':
      PIN_NUMBER='(3)';
      BIDIRECTIONAL='TRUE';
      INPUT_LOAD='(-0.01,0.01)';
      OUTPUT_LOAD='(1.0,-1.0)';
    '2Y3':
      PIN_NUMBER='(4)';
      BIDIRECTIONAL='TRUE';
      INPUT_LOAD='(-0.01,0.01)';
      OUTPUT_LOAD='(1.0,-1.0)';
    '2Y1':
      PIN_NUMBER='(5)';
      BIDIRECTIONAL='TRUE';
      INPUT_LOAD='(-0.01,0.01)';
      OUTPUT_LOAD='(1.0,-1.0)';
    '-E':
      PIN_NUMBER='(6)';
      BIDIRECTIONAL='TRUE';
      INPUT_LOAD='(-0.01,0.01)';
      OUTPUT_LOAD='(1.0,-1.0)';
    'VEE':
      PIN_NUMBER='(7)';
      PINUSE='POWER';
      NO_LOAD_CHECK='Both';
      NO_IO_CHECK='Both';
      NO_ASSERT_CHECK='TRUE';
      NO_DIR_CHECK='TRUE';
      ALLOW_CONNECT='TRUE';
    'GND':
      PIN_NUMBER='(8)';
      PINUSE='POWER';
      NO_LOAD_CHECK='Both';
      NO_IO_CHECK='Both';
      NO_ASSERT_CHECK='TRUE';
      NO_DIR_CHECK='TRUE';
      ALLOW_CONNECT='TRUE';
    'S1':
      PIN_NUMBER='(9)';
      BIDIRECTIONAL='TRUE';
      INPUT_LOAD='(-0.01,0.01)';
      OUTPUT_LOAD='(1.0,-1.0)';
    'S0':
      PIN_NUMBER='(10)';
      BIDIRECTIONAL='TRUE';
      INPUT_LOAD='(-0.01,0.01)';
      OUTPUT_LOAD='(1.0,-1.0)';
    '1Y3':
      PIN_NUMBER='(11)';
      BIDIRECTIONAL='TRUE';
      INPUT_LOAD='(-0.01,0.01)';
      OUTPUT_LOAD='(1.0,-1.0)';
    '1Y0':
      PIN_NUMBER='(12)';
      BIDIRECTIONAL='TRUE';
      INPUT_LOAD='(-0.01,0.01)';
      OUTPUT_LOAD='(1.0,-1.0)';
    '1Z':
      PIN_NUMBER='(13)';
      BIDIRECTIONAL='TRUE';
      INPUT_LOAD='(-0.01,0.01)';
      OUTPUT_LOAD='(1.0,-1.0)';
    '1Y1':
      PIN_NUMBER='(14)';
      BIDIRECTIONAL='TRUE';
      INPUT_LOAD='(-0.01,0.01)';
      OUTPUT_LOAD='(1.0,-1.0)';
    '1Y2':
      PIN_NUMBER='(15)';
      BIDIRECTIONAL='TRUE';
      INPUT_LOAD='(-0.01,0.01)';
      OUTPUT_LOAD='(1.0,-1.0)';
    'VCC':
      PIN_NUMBER='(16)';
      PINUSE='POWER';
      NO_LOAD_CHECK='Both';
      NO_IO_CHECK='Both';
      NO_ASSERT_CHECK='TRUE';
      NO_DIR_CHECK='TRUE';
      ALLOW_CONNECT='TRUE';
  end_pin;
  body
    PART_NAME='74LV4052PW';
    BODY_NAME='74LV4052PW';
    PHYS_DES_PREFIX='U';
    CLASS='IC';
  end_body;
end_primitive;

END.
